(kicad_pcb
	(version 20221018)
	(generator pcbnew)
	(general
    (thickness 1.6)
  )
	(paper "A4")
	(title_block
    (title "NUC Computer Cluster Power Breakout HW")
    (date "2023-10-18")
    (rev "1.4.3")
    (company "Antmicro Ltd.")
		(comment 9 "footprints 110-116 of 234")
	)
	(layers
    (0 "F.Cu" mixed)
    (1 "In1.Cu" power)
    (2 "In2.Cu" mixed)
    (31 "B.Cu" power)
    (32 "B.Adhes" user "B.Adhesive")
    (33 "F.Adhes" user "F.Adhesive")
    (34 "B.Paste" user)
    (35 "F.Paste" user)
    (36 "B.SilkS" user "B.Silkscreen")
    (37 "F.SilkS" user "F.Silkscreen")
    (38 "B.Mask" user)
    (39 "F.Mask" user)
    (40 "Dwgs.User" user "User.Drawings")
    (41 "Cmts.User" user "User.Comments")
    (42 "Eco1.User" user "User.Eco1")
    (43 "Eco2.User" user "User.Eco2")
    (44 "Edge.Cuts" user)
    (45 "Margin" user)
    (46 "B.CrtYd" user "B.Courtyard")
    (47 "F.CrtYd" user "F.Courtyard")
    (48 "B.Fab" user)
    (49 "F.Fab" user)
  )
	(footprint "antmicro-footprints:SOIC-8_3.9x4.9x1.75mm_P1.27mm" (layer "F.Cu")
    (at 176.7 106.3 90)
    (property "Author" "Antmicro")
    (property "License" "Apache-2.0")
    (property "MPN" "ISO1641BDR")
    (property "Manufacturer" "Texas Instruments")
    (property "Sheetfile" "ftdi-module.kicad_sch")
    (property "Sheetname" "FTDI")
    (property "ki_description" "Bidirectional Optoisolator")
    (property "ki_keywords" "SMT, OPTOCOUPLER, IC, INTERFACE, I2C, ISOLATOR")
    (attr smd)
    (fp_text reference "U2" (at 3.8 -1.2 180) (layer "F.SilkS")
        (effects (font (size 0.7 0.7) (thickness 0.15)) (justify left bottom))
    )
    (fp_text value "ISO1641" (at 0 3.65 90) (layer "F.Fab")
        (effects (font (size 0.7 0.7) (thickness 0.15)) (justify left bottom))
    )
    (fp_text user "${REFERENCE}" (at -3.476 7.099 90) (layer "F.Fab") hide
        (effects (font (size 0.7 0.7) (thickness 0.15)) (justify left bottom))
    )
    (fp_text user "License: Apache-2.0" (at -3.476 5.099 90) (layer "F.Fab") hide
        (effects (font (size 0.7 0.7) (thickness 0.15)) (justify left bottom))
    )
    (fp_text user "Author: Antmicro" (at -3.476 6.099 90) (layer "F.Fab") hide
        (effects (font (size 0.7 0.7) (thickness 0.15)) (justify left bottom))
    )
    (fp_line (start -1.95 -2.452) (end 1.95 -2.45)
      (stroke (width 0.15) (type solid)) (layer "F.SilkS"))
    (fp_line (start -1.95 2.45) (end 1.95 2.45)
      (stroke (width 0.15) (type solid)) (layer "F.SilkS"))
    (fp_circle (center -2.4 -2.45) (end -2.35 -2.4)
      (stroke (width 0.15) (type solid)) (fill solid) (layer "F.SilkS"))
    (fp_rect (start -3.625 -2.7) (end 3.625 2.7)
      (stroke (width 0.05) (type solid)) (fill none) (layer "F.CrtYd"))
    (fp_line (start -1.95 -1.18) (end -0.683 -2.452)
      (stroke (width 0.15) (type solid)) (layer "F.Fab"))
    (fp_line (start -1.95 2.45) (end -1.95 -1.18)
      (stroke (width 0.15) (type solid)) (layer "F.Fab"))
    (fp_line (start -0.683 -2.452) (end 1.949 -2.452)
      (stroke (width 0.15) (type solid)) (layer "F.Fab"))
    (fp_line (start 1.949 -2.452) (end 1.949 2.45)
      (stroke (width 0.15) (type solid)) (layer "F.Fab"))
    (fp_line (start 1.949 2.45) (end -1.95 2.45)
      (stroke (width 0.15) (type solid)) (layer "F.Fab"))
    (pad "1" smd roundrect (at -2.714 -1.905 180) (size 0.65 1.525) (layers "F.Cu" "F.Paste" "F.Mask") (roundrect_rratio 0.25)
      (net 76 "VCC3V3_USB") (pinfunction "VCC1") (pintype "power_in"))
    (pad "2" smd roundrect (at -2.714 -0.635 180) (size 0.65 1.525) (layers "F.Cu" "F.Paste" "F.Mask") (roundrect_rratio 0.25)
      (net 80 "SDA_FTDI") (pinfunction "SDA1") (pintype "bidirectional"))
    (pad "3" smd roundrect (at -2.714 0.632 180) (size 0.65 1.525) (layers "F.Cu" "F.Paste" "F.Mask") (roundrect_rratio 0.25)
      (net 81 "SCL_FTDI") (pinfunction "SCL1") (pintype "bidirectional"))
    (pad "4" smd roundrect (at -2.714 1.902 180) (size 0.65 1.525) (layers "F.Cu" "F.Paste" "F.Mask") (roundrect_rratio 0.25)
      (net 77 "GNDD") (pinfunction "GND1") (pintype "power_in"))
    (pad "5" smd roundrect (at 2.712 1.902 180) (size 0.65 1.525) (layers "F.Cu" "F.Paste" "F.Mask") (roundrect_rratio 0.25)
      (net 4 "GND") (pinfunction "GND2") (pintype "power_in"))
    (pad "6" smd roundrect (at 2.712 0.632 180) (size 0.65 1.525) (layers "F.Cu" "F.Paste" "F.Mask") (roundrect_rratio 0.25)
      (net 17 "SCL") (pinfunction "SCL2") (pintype "bidirectional"))
    (pad "7" smd roundrect (at 2.712 -0.635 180) (size 0.65 1.525) (layers "F.Cu" "F.Paste" "F.Mask") (roundrect_rratio 0.25)
      (net 18 "SDA") (pinfunction "SDA2") (pintype "bidirectional"))
    (pad "8" smd roundrect (at 2.712 -1.905 180) (size 0.65 1.525) (layers "F.Cu" "F.Paste" "F.Mask") (roundrect_rratio 0.25)
      (net 1 "VCC3V3") (pinfunction "VCC2") (pintype "power_in"))
  )
	(footprint "antmicro-footprints:TSOT23-6" (layer "F.Cu")
    (at 107.147132 99.076324 90)
    (property "Author" "Antmicro")
    (property "License" "Apache-2.0")
    (property "MPN" "AP62301WU-7")
    (property "Manufacturer" "Diodes Incorporated")
    (property "Sheetfile" "daughterboard-supply.kicad_sch")
    (property "Sheetname" "daughterboard-supply")
    (property "ki_description" "DC-DC Switching Synchronous Buck Regulator, Adjustable, 4.2V-18Vin, 0.8V-7V/3A out, TSOT-26-6")
    (property "ki_keywords" "SMT, PMIC, IC, VOLTAGE")
    (attr smd)
    (fp_text reference "U4" (at 2.276324 2.652868 90) (layer "F.SilkS")
        (effects (font (size 0.7 0.7) (thickness 0.15)) (justify right bottom))
    )
    (fp_text value "AP62301_TSOT" (at 0 2.6 90) (layer "F.Fab")
        (effects (font (size 0.7 0.7) (thickness 0.15)) (justify left bottom))
    )
    (fp_text user "${REFERENCE}" (at -1.93 3.8 90) (layer "F.Fab") hide
        (effects (font (size 0.7 0.7) (thickness 0.15)) (justify left bottom))
    )
    (fp_text user "Author: Antmicro" (at -1.93 5 90) (layer "F.Fab") hide
        (effects (font (size 0.7 0.7) (thickness 0.15)) (justify left bottom))
    )
    (fp_text user "License: Apache-2.0" (at -1.93 6.199 90) (layer "F.Fab") hide
        (effects (font (size 0.7 0.7) (thickness 0.15)) (justify left bottom))
    )
    (fp_line (start -1 -1.5) (end -1 -1.375)
      (stroke (width 0.15) (type solid)) (layer "F.SilkS"))
    (fp_line (start -1 1.55) (end -1 1.4)
      (stroke (width 0.15) (type solid)) (layer "F.SilkS"))
    (fp_line (start 1 -1.497) (end -1 -1.5)
      (stroke (width 0.15) (type solid)) (layer "F.SilkS"))
    (fp_line (start 1 -1.497) (end 1 -1.375)
      (stroke (width 0.15) (type solid)) (layer "F.SilkS"))
    (fp_line (start 1 1.55) (end -1 1.55)
      (stroke (width 0.15) (type solid)) (layer "F.SilkS"))
    (fp_line (start 1 1.55) (end 1 1.4)
      (stroke (width 0.15) (type solid)) (layer "F.SilkS"))
    (fp_circle (center -1.44 -1.5) (end -1.39 -1.5)
      (stroke (width 0.15) (type solid)) (fill solid) (layer "F.SilkS"))
    (fp_rect (start 1.93 -1.7) (end -1.93 1.7)
      (stroke (width 0.05) (type solid)) (fill none) (layer "F.CrtYd"))
    (fp_line (start -0.45 -1.521) (end -0.876 -1.096)
      (stroke (width 0.15) (type solid)) (layer "F.Fab"))
    (fp_rect (start 0.875 1.528) (end -0.875 -1.525)
      (stroke (width 0.15) (type solid)) (fill none) (layer "F.Fab"))
    (pad "1" smd rect (at -1.301 -0.947) (size 0.7 1.2) (layers "F.Cu" "F.Paste" "F.Mask")
      (net 4 "GND") (pinfunction "GND") (pintype "power_in"))
    (pad "2" smd rect (at -1.301 0.004) (size 0.7 1.2) (layers "F.Cu" "F.Paste" "F.Mask")
      (net 32 "Net-(U4-SW)") (pinfunction "SW") (pintype "power_out"))
    (pad "3" smd rect (at -1.301 0.954) (size 0.7 1.2) (layers "F.Cu" "F.Paste" "F.Mask")
      (net 11 "VCC12V0") (pinfunction "VIN") (pintype "power_in"))
    (pad "4" smd rect (at 1.299 0.954) (size 0.7 1.2) (layers "F.Cu" "F.Paste" "F.Mask")
      (net 112 "Net-(U4-FB)") (pinfunction "FB") (pintype "input"))
    (pad "5" smd rect (at 1.299 0.004) (size 0.7 1.2) (layers "F.Cu" "F.Paste" "F.Mask")
      (net 120 "unconnected-(U4-EN-Pad5)") (pinfunction "EN") (pintype "input+no_connect"))
    (pad "6" smd rect (at 1.299 -0.947) (size 0.7 1.2) (layers "F.Cu" "F.Paste" "F.Mask")
      (net 16 "Net-(U4-BST)") (pinfunction "BST") (pintype "output"))
  )
	(footprint "antmicro-footprints:TP_SMD_1mm" (layer "F.Cu")
    (at 187.55 121.825 180)
    (property "Author" "Antmicro")
    (property "License" "Apache-2.0")
    (property "MPN" "")
    (property "Manufacturer" "")
    (property "Sheetfile" "ftdi-module.kicad_sch")
    (property "Sheetname" "FTDI")
    (property "exclude_from_bom" "")
    (property "ki_description" "Test point 1mm SMD")
    (property "ki_keywords" "TESTPOINT")
    (attr exclude_from_pos_files exclude_from_bom)
    (fp_text reference "5V_USB1" (at -1.55 -3.875 270) (layer "F.SilkS")
        (effects (font (size 0.7 0.7) (thickness 0.15)) (justify left bottom))
    )
    (fp_text value "TP_1mm_SMD" (at 0 1.4 180) (layer "F.Fab")
        (effects (font (size 0.7 0.7) (thickness 0.15)) (justify left bottom))
    )
    (fp_text user "License: Apache-2.0" (at -0.5 5.2 180) (layer "F.Fab") hide
        (effects (font (size 0.7 0.7) (thickness 0.15)) (justify left bottom))
    )
    (fp_text user "${REFERENCE}" (at -0.5 2.8 180) (layer "F.Fab") hide
        (effects (font (size 0.7 0.7) (thickness 0.15)) (justify left bottom))
    )
    (fp_text user "Author: Antmicro" (at -0.5 4 180) (layer "F.Fab") hide
        (effects (font (size 0.7 0.7) (thickness 0.15)) (justify left bottom))
    )
    (fp_circle (center 0 0) (end 0.6 0)
      (stroke (width 0.05) (type default)) (fill none) (layer "F.CrtYd"))
    (pad "1" smd circle (at 0 0 180) (size 1 1) (layers "F.Cu" "F.Mask")
      (net 3 "VCC5V0_USB") (pinfunction "1") (pintype "passive"))
  )
	(footprint "antmicro-footprints:SOT-23-5" (layer "F.Cu")
    (at 185.05 122.225 -90)
    (property "Author" "Antmicro")
    (property "License" "Apache-2.0")
    (property "MPN" "NCP163ASN330T1G")
    (property "Manufacturer" "ON Semiconductor")
    (property "Sheetfile" "ftdi-module.kicad_sch")
    (property "Sheetname" "FTDI")
    (property "ki_description" "Fixed LDO Voltage Regulator, 2.2V to 5.5V, 105mV drop, 3.3V/250mA out, SOT-23-5")
    (property "ki_keywords" "SMT, PMIC, IC, LDO, VOLTAGE, REGULATOR")
    (attr smd)
    (fp_text reference "U3" (at -0.875 1.85 90) (layer "F.SilkS")
        (effects (font (size 0.7 0.7) (thickness 0.15)) (justify right bottom))
    )
    (fp_text value "NCP163ASN330T1G" (at 0.002 2.799 90) (layer "F.Fab")
        (effects (font (size 0.7 0.7) (thickness 0.15)) (justify right bottom))
    )
    (fp_text user "${REFERENCE}" (at -1.898 4.299 90) (layer "F.Fab") hide
        (effects (font (size 0.7 0.7) (thickness 0.15)) (justify right bottom))
    )
    (fp_text user "Author: Antmicro" (at -1.898 5.499 90) (layer "F.Fab") hide
        (effects (font (size 0.7 0.7) (thickness 0.15)) (justify right bottom))
    )
    (fp_text user "License: Apache-2.0" (at -1.898 6.7 90) (layer "F.Fab") hide
        (effects (font (size 0.7 0.7) (thickness 0.15)) (justify right bottom))
    )
    (fp_line (start -0.85 1.6) (end -0.85 1.301)
      (stroke (width 0.15) (type solid)) (layer "F.SilkS"))
    (fp_line (start -0.8 -1.6) (end -0.8 -1.3)
      (stroke (width 0.15) (type solid)) (layer "F.SilkS"))
    (fp_line (start -0.8 -1.6) (end -0.5 -1.6)
      (stroke (width 0.15) (type solid)) (layer "F.SilkS"))
    (fp_line (start -0.55 1.6) (end -0.85 1.6)
      (stroke (width 0.15) (type solid)) (layer "F.SilkS"))
    (fp_line (start 0.8 -1.6) (end 0.5 -1.6)
      (stroke (width 0.15) (type solid)) (layer "F.SilkS"))
    (fp_line (start 0.8 -1.3) (end 0.8 -1.6)
      (stroke (width 0.15) (type solid)) (layer "F.SilkS"))
    (fp_line (start 0.8 0.55) (end 0.8 -0.55)
      (stroke (width 0.15) (type solid)) (layer "F.SilkS"))
    (fp_line (start 0.8 1.3) (end 0.8 1.599)
      (stroke (width 0.15) (type solid)) (layer "F.SilkS"))
    (fp_line (start 0.8 1.599) (end 0.549 1.599)
      (stroke (width 0.15) (type solid)) (layer "F.SilkS"))
    (fp_circle (center -1.25 -1.5) (end -1.2 -1.5)
      (stroke (width 0.15) (type solid)) (fill solid) (layer "F.SilkS"))
    (fp_rect (start 1.9 -1.76) (end -1.9 1.75)
      (stroke (width 0.05) (type solid)) (fill none) (layer "F.CrtYd"))
    (fp_line (start -0.398 -1.526) (end -0.874 -1.05)
      (stroke (width 0.15) (type solid)) (layer "F.Fab"))
    (fp_rect (start 0.874 1.523) (end -0.873 -1.525)
      (stroke (width 0.15) (type solid)) (fill none) (layer "F.Fab"))
    (pad "1" smd rect (at -1.351 -0.951 180) (size 0.55 1) (layers "F.Cu" "F.Paste" "F.Mask")
      (net 3 "VCC5V0_USB") (pinfunction "VIN") (pintype "power_in"))
    (pad "2" smd rect (at -1.351 0 180) (size 0.55 1) (layers "F.Cu" "F.Paste" "F.Mask")
      (net 77 "GNDD") (pinfunction "GND") (pintype "power_in"))
    (pad "3" smd rect (at -1.351 0.949 180) (size 0.55 1) (layers "F.Cu" "F.Paste" "F.Mask")
      (net 3 "VCC5V0_USB") (pinfunction "EN") (pintype "input"))
    (pad "4" smd rect (at 1.35 0.949 180) (size 0.55 1) (layers "F.Cu" "F.Paste" "F.Mask")
      (net 119 "unconnected-(U3-NC-Pad4)") (pinfunction "NC") (pintype "no_connect"))
    (pad "5" smd rect (at 1.35 -0.951 180) (size 0.55 1) (layers "F.Cu" "F.Paste" "F.Mask")
      (net 76 "VCC3V3_USB") (pinfunction "VOUT") (pintype "power_out"))
  )
	(footprint "antmicro-footprints:R_0603_1608Metric" (layer "F.Cu")
    (at 180.225 106.25 90)
    (descr "Resistor SMD 0603")
    (tags "resistor SMD 0603")
    (property "Author" "Antmicro")
    (property "Current" "1A")
    (property "DNP" "DNP")
    (property "License" "Apache-2.0")
    (property "MPN" "CR0603-J/-000ELF")
    (property "Manufacturer" "Bourns")
    (property "Sheetfile" "ftdi-module.kicad_sch")
    (property "Sheetname" "FTDI")
    (property "Tolerance" "")
    (property "Val" "0R")
    (property "dnp" "")
    (property "exclude_from_bom" "")
    (property "ki_description" "Zero Ohm Resistor, Jumper, 0603 [1608 Metric], Thick Film, 100 mW, 1 A, Surface Mount Device, CR")
    (property "ki_keywords" "0603, SMT, RESISTOR, PASSIVE")
    (attr smd exclude_from_bom)
    (fp_text reference "R39" (at -0.05 1.775 90) (layer "F.SilkS")
        (effects (font (size 0.7 0.7) (thickness 0.15)) (justify left bottom))
    )
    (fp_text value "R_0R_0603" (at 0 1.6 90) (layer "F.Fab")
        (effects (font (size 0.7 0.7) (thickness 0.15)) (justify left bottom))
    )
    (fp_text user "${REFERENCE}" (at -1.25 3.898 90) (layer "F.Fab") hide
        (effects (font (size 0.7 0.7) (thickness 0.15)) (justify left bottom))
    )
    (fp_text user "Author: Antmicro" (at -1.25 4.9 90) (layer "F.Fab") hide
        (effects (font (size 0.7 0.7) (thickness 0.15)) (justify left bottom))
    )
    (fp_text user "License: Apache-2.0" (at -1.25 5.9 90) (layer "F.Fab") hide
        (effects (font (size 0.7 0.7) (thickness 0.15)) (justify left bottom))
    )
    (fp_line (start -0.15 -0.4) (end 0.15 -0.4)
      (stroke (width 0.15) (type solid)) (layer "F.SilkS"))
    (fp_line (start -0.15 0.4) (end 0.15 0.4)
      (stroke (width 0.15) (type solid)) (layer "F.SilkS"))
    (fp_rect (start -1.25 -0.65) (end 1.25 0.65)
      (stroke (width 0.05) (type solid)) (fill none) (layer "F.CrtYd"))
    (fp_rect (start -0.8 -0.4) (end 0.8 0.4)
      (stroke (width 0.15) (type solid)) (fill none) (layer "F.Fab"))
    (pad "1" smd roundrect (at -0.7 0 90) (size 0.8 1) (layers "F.Cu" "F.Paste" "F.Mask") (roundrect_rratio 0.2)
      (net 81 "SCL_FTDI") (pintype "passive"))
    (pad "2" smd roundrect (at 0.7 0 90) (size 0.8 1) (layers "F.Cu" "F.Paste" "F.Mask") (roundrect_rratio 0.2)
      (net 17 "SCL") (pintype "passive"))
  )
	(footprint "antmicro-footprints:C_0402_1005Metric" (layer "F.Cu")
    (at 162.8 103.7 180)
    (descr "Capacitor SMD 0402")
    (tags "capacitor SMD 0402")
    (property "Author" "Antmicro")
    (property "Dielectric" "X5R")
    (property "License" "Apache-2.0")
    (property "MPN" "GRM155R61H104KE14D")
    (property "Manufacturer" "Murata")
    (property "Sheetfile" "pow-cycl-curr-meas.kicad_sch")
    (property "Sheetname" "Power Cycling & Current Measurement")
    (property "Val" "100n")
    (property "Voltage" "50V")
    (property "ki_description" "SMD Multilayer Ceramic Capacitor, 0.1 µF, 50 V, 0402 [1005 Metric], ± 10%, X5R, GRM Series")
    (property "ki_keywords" "0402, SMT, CAPACITOR, PASSIVE, CERAMIC, MLCC")
    (attr smd)
    (fp_text reference "C21" (at -1.2 -1.45) (layer "F.SilkS")
        (effects (font (size 0.7 0.7) (thickness 0.15)) (justify right bottom))
    )
    (fp_text value "C_100n_0402" (at -1.022927 2.155213) (layer "F.Fab")
        (effects (font (size 0.7 0.7) (thickness 0.15)) (justify right bottom))
    )
    (fp_text user "License: Apache-2.0" (at -0.939 5.799) (layer "F.Fab") hide
        (effects (font (size 0.7 0.7) (thickness 0.15)) (justify right bottom))
    )
    (fp_text user "${REFERENCE}" (at -0.939 4.599) (layer "F.Fab") hide
        (effects (font (size 0.7 0.7) (thickness 0.15)) (justify right bottom))
    )
    (fp_text user "Author: Antmicro" (at -0.939 3.399) (layer "F.Fab") hide
        (effects (font (size 0.7 0.7) (thickness 0.15)) (justify right bottom))
    )
    (fp_rect (start -0.925 -0.47) (end 0.925 0.47)
      (stroke (width 0.05) (type default)) (fill none) (layer "F.CrtYd"))
    (fp_line (start -0.494 -0.25) (end 0.504 -0.25)
      (stroke (width 0.15) (type solid)) (layer "F.Fab"))
    (fp_line (start -0.494 0.248) (end -0.494 -0.25)
      (stroke (width 0.15) (type solid)) (layer "F.Fab"))
    (fp_line (start 0.504 -0.25) (end 0.504 0.248)
      (stroke (width 0.15) (type solid)) (layer "F.Fab"))
    (fp_line (start 0.504 0.248) (end -0.494 0.248)
      (stroke (width 0.15) (type solid)) (layer "F.Fab"))
    (pad "1" smd roundrect (at -0.48 0 180) (size 0.59 0.64) (layers "F.Cu" "F.Paste" "F.Mask") (roundrect_rratio 0.25)
      (net 4 "GND") (pintype "passive"))
    (pad "2" smd roundrect (at 0.48 0 180) (size 0.59 0.64) (layers "F.Cu" "F.Paste" "F.Mask") (roundrect_rratio 0.25)
      (net 1 "VCC3V3") (pintype "passive"))
  )
	(footprint "antmicro-footprints:C_0402_1005Metric" (layer "F.Cu")
    (at 168.5 117.45 90)
    (descr "Capacitor SMD 0402")
    (tags "capacitor SMD 0402")
    (property "Author" "Antmicro")
    (property "Dielectric" "")
    (property "License" "Apache-2.0")
    (property "MPN" "GRM155R61A475MEAAD")
    (property "Manufacturer" "Murata")
    (property "Sheetfile" "ftdi-module.kicad_sch")
    (property "Sheetname" "FTDI")
    (property "Val" "4u7")
    (property "Voltage" "")
    (property "ki_description" "SMD Multilayer Ceramic Capacitor, 4.7 µF, 10 V, 0402 [1005 Metric], ± 20%, X5R, GRM Series")
    (property "ki_keywords" "0402, SMT, CAPACITOR, PASSIVE")
    (attr smd)
    (fp_text reference "C11" (at 0.9 0.4 90) (layer "F.SilkS")
        (effects (font (size 0.7 0.7) (thickness 0.15)) (justify left bottom))
    )
    (fp_text value "C_4u7_0402" (at -1.022927 2.155213 90) (layer "F.Fab")
        (effects (font (size 0.7 0.7) (thickness 0.15)) (justify left bottom))
    )
    (fp_text user "Author: Antmicro" (at -0.939 3.399 90) (layer "F.Fab") hide
        (effects (font (size 0.7 0.7) (thickness 0.15)) (justify left bottom))
    )
    (fp_text user "License: Apache-2.0" (at -0.939 5.799 90) (layer "F.Fab") hide
        (effects (font (size 0.7 0.7) (thickness 0.15)) (justify left bottom))
    )
    (fp_text user "${REFERENCE}" (at -0.939 4.599 90) (layer "F.Fab") hide
        (effects (font (size 0.7 0.7) (thickness 0.15)) (justify left bottom))
    )
    (fp_rect (start -0.925 -0.47) (end 0.925 0.47)
      (stroke (width 0.05) (type default)) (fill none) (layer "F.CrtYd"))
    (fp_line (start -0.494 -0.25) (end 0.504 -0.25)
      (stroke (width 0.15) (type solid)) (layer "F.Fab"))
    (fp_line (start -0.494 0.248) (end -0.494 -0.25)
      (stroke (width 0.15) (type solid)) (layer "F.Fab"))
    (fp_line (start 0.504 -0.25) (end 0.504 0.248)
      (stroke (width 0.15) (type solid)) (layer "F.Fab"))
    (fp_line (start 0.504 0.248) (end -0.494 0.248)
      (stroke (width 0.15) (type solid)) (layer "F.Fab"))
    (pad "1" smd roundrect (at -0.48 0 90) (size 0.59 0.64) (layers "F.Cu" "F.Paste" "F.Mask") (roundrect_rratio 0.25)
      (net 6 "/FTDI/FTDI_VPLL") (pintype "passive"))
    (pad "2" smd roundrect (at 0.48 0 90) (size 0.59 0.64) (layers "F.Cu" "F.Paste" "F.Mask") (roundrect_rratio 0.25)
      (net 77 "GNDD") (pintype "passive"))
  )
)
